# BASEBOARD_FAB2 (Tioga Pass) — schematic netlist excerpt (pin names and nets, part order shuffled) for the footprints in the layout excerpt that follows; sources: Cadence DE-HDL packaged netlist, KiCad conversion of Wiwynn_Tioga_Pass_MB.brd

R1T25  RES  8.2K 1% CHIP  pkg 0402  page 146 : A = A_USB2BVRES ; B = GND
C8B3  CAP_A  22.0UF 4V 20% X6S  pkg 0603V  page 130 : A = P1V8_PCH_STBY ; B = GND
C5A1  CAP_A  47UF 4V 20% X5R  pkg 0603V  page 220 : A = PVDDQ_DEF ; B = GND

(kicad_pcb
	(version 20260206)
	(generator "pcbnew")
	(generator_version "10.0")
	(general
		(thickness 1.6)
		(legacy_teardrops no)
	)
	(paper "A4")
	(title_block
		(title "Wiwynn_Tioga_Pass_MB.brd")
		(comment 1 "Tioga Pass / footprints 731-733 of 4770")
	)
	(layers
		(0 "F.Cu" signal "TOP")
		(4 "In1.Cu" signal "L2GND")
		(6 "In2.Cu" signal "L3")
		(8 "In3.Cu" signal "L4GND")
		(10 "In4.Cu" signal "L5")
		(12 "In5.Cu" signal "L6GND")
		(14 "In6.Cu" signal "L7VCC")
		(16 "In7.Cu" signal "L8VCC")
		(18 "In8.Cu" signal "L9GND")
		(20 "In9.Cu" signal "L10")
		(22 "In10.Cu" signal "L11GND")
		(24 "In11.Cu" signal "L12")
		(26 "In12.Cu" signal "L13GND")
		(2 "B.Cu" signal "BOTTOM")
		(9 "F.Adhes" user "F.Adhesive")
		(11 "B.Adhes" user "B.Adhesive")
		(13 "F.Paste" user "Package Geometry/Pastemask Top")
		(15 "B.Paste" user "Package Geometry/Pastemask Bottom")
		(5 "F.SilkS" user "Ref Des/Silkscreen Top")
		(7 "B.SilkS" user "Ref Des/Silkscreen Bottom")
		(1 "F.Mask" user "Board Geometry/Soldermask Top")
		(3 "B.Mask" user "Board Geometry/Soldermask Bottom")
		(17 "Dwgs.User" user "User.Drawings")
		(19 "Cmts.User" user "User.Comments")
		(21 "Eco1.User" user "User.Eco1")
		(23 "Eco2.User" user "User.Eco2")
		(25 "Edge.Cuts" user "Board Geometry/Outline")
		(27 "Margin" user)
		(31 "F.CrtYd" user "Package Geometry/Place Bound Top")
		(29 "B.CrtYd" user "Package Geometry/Place Bound Bottom")
		(35 "F.Fab" user "Ref Des/Assembly Top")
		(33 "B.Fab" user "Ref Des/Assembly Bottom")
	)
	(footprint ""
		(layer "F.Cu")
		(at 401.17014 -30.67304 -90)
		(property "Reference" "R1T25"
			(at 0 0 270)
			(layer "F.SilkS")
			(hide yes)
			(effects
				(font
					(size 1.27 1.27)
				)
			)
		)
		(property "Value" ""
			(at 0 0 270)
			(layer "F.Fab")
			(effects
				(font
					(size 1.27 1.27)
				)
			)
		)
		(duplicate_pad_numbers_are_jumpers no)
		(fp_poly
			(pts
				(xy -0.2794 -0.1016) (xy 0.2794 -0.1016) (xy 0.2794 0.9906) (xy -0.2794 0.9906)
			)
			(stroke
				(width 0)
				(type default)
			)
			(fill no)
			(layer "F.CrtYd")
		)
		(fp_line
			(start -0.2794 0.9906)
			(end 0.2794 0.9906)
			(stroke
				(width 0.1)
				(type default)
			)
			(layer "F.Fab")
		)
		(fp_line
			(start 0.2794 0.9906)
			(end 0.2794 -0.1016)
			(stroke
				(width 0.1)
				(type default)
			)
			(layer "F.Fab")
		)
		(fp_line
			(start -0.2794 -0.1016)
			(end -0.2794 0.9906)
			(stroke
				(width 0.1)
				(type default)
			)
			(layer "F.Fab")
		)
		(fp_line
			(start 0.2794 -0.1016)
			(end -0.2794 -0.1016)
			(stroke
				(width 0.1)
				(type default)
			)
			(layer "F.Fab")
		)
		(pad "1" smd rect
			(at 0 0 270)
			(size 0.508 0.508)
			(layers "F.Cu" "F.Mask" "F.Paste")
			(net "A_USB2BVRES")
		)
		(pad "2" smd rect
			(at 0 0.889 270)
			(size 0.508 0.508)
			(layers "F.Cu" "F.Mask" "F.Paste")
			(net "GND")
		)
		(zone
			(layer "F.Cu")
			(hatch none 0.5)
			(connect_pads
				(clearance 0)
			)
			(min_thickness 0.25)
			(keepout
				(tracks not_allowed)
				(vias allowed)
				(pads allowed)
				(copperpour not_allowed)
				(footprints allowed)
			)
			(placement
				(enabled no)
				(sheetname "")
			)
			(fill
				(thermal_gap 0.5)
				(thermal_bridge_width 0.5)
				(island_removal_mode 0)
			)
			(polygon
				(pts
					(xy 400.53514 -30.92704) (xy 400.53514 -30.41904) (xy 400.91614 -30.41904) (xy 400.91614 -30.92704)
				)
			)
		)
		(zone
			(layer "F.Cu")
			(hatch none 0.5)
			(connect_pads
				(clearance 0)
			)
			(min_thickness 0.25)
			(keepout
				(tracks allowed)
				(vias not_allowed)
				(pads allowed)
				(copperpour not_allowed)
				(footprints allowed)
			)
			(placement
				(enabled no)
				(sheetname "")
			)
			(fill
				(thermal_gap 0.5)
				(thermal_bridge_width 0.5)
				(island_removal_mode 0)
			)
			(polygon
				(pts
					(xy 400.91614 -30.92704) (xy 400.91614 -30.41904) (xy 400.53514 -30.41904) (xy 400.53514 -30.92704)
				)
			)
		)
	)
	(footprint ""
		(layer "F.Cu")
		(at 401.2438 -130.1496 180)
		(property "Reference" "C8B3"
			(at 0 0 180)
			(layer "F.SilkS")
			(hide yes)
			(effects
				(font
					(size 1.27 1.27)
				)
			)
		)
		(property "Value" ""
			(at 0 0 180)
			(layer "F.Fab")
			(effects
				(font
					(size 1.27 1.27)
				)
			)
		)
		(duplicate_pad_numbers_are_jumpers no)
		(fp_poly
			(pts
				(xy -0.4953 -0.2032) (xy 0.4953 -0.2032) (xy 0.4953 1.6002) (xy -0.4953 1.6002)
			)
			(stroke
				(width 0)
				(type default)
			)
			(fill no)
			(layer "F.CrtYd")
		)
		(fp_line
			(start 0.4953 1.6002)
			(end -0.4953 1.6002)
			(stroke
				(width 0.1)
				(type default)
			)
			(layer "F.Fab")
		)
		(fp_line
			(start 0.4953 -0.2032)
			(end 0.4953 1.6002)
			(stroke
				(width 0.1)
				(type default)
			)
			(layer "F.Fab")
		)
		(fp_line
			(start -0.4953 1.6002)
			(end -0.4953 -0.2032)
			(stroke
				(width 0.1)
				(type default)
			)
			(layer "F.Fab")
		)
		(fp_line
			(start -0.4953 -0.2032)
			(end 0.4953 -0.2032)
			(stroke
				(width 0.1)
				(type default)
			)
			(layer "F.Fab")
		)
		(pad "1" smd rect
			(at 0 0 180)
			(size 0.762 0.889)
			(layers "F.Cu" "F.Mask" "F.Paste")
			(net "P1V8_PCH_STBY")
		)
		(pad "2" smd rect
			(at 0 1.397 180)
			(size 0.762 0.889)
			(layers "F.Cu" "F.Mask" "F.Paste")
			(net "GND")
		)
		(zone
			(layer "F.Cu")
			(hatch none 0.5)
			(connect_pads
				(clearance 0)
			)
			(min_thickness 0.25)
			(keepout
				(tracks not_allowed)
				(vias allowed)
				(pads allowed)
				(copperpour not_allowed)
				(footprints allowed)
			)
			(placement
				(enabled no)
				(sheetname "")
			)
			(fill
				(thermal_gap 0.5)
				(thermal_bridge_width 0.5)
				(island_removal_mode 0)
			)
			(polygon
				(pts
					(xy 401.6248 -130.5941) (xy 400.8628 -130.5941) (xy 400.8628 -131.1021) (xy 401.6248 -131.1021)
				)
			)
		)
	)
	(footprint ""
		(layer "F.Cu")
		(at 245.7323 -149.8092 -90)
		(property "Reference" "C5A1"
			(at 1.848866 0.752348 270)
			(unlocked yes)
			(layer "F.SilkS")
			(effects
				(font
					(size 1.27 0.9652)
					(thickness 0.1524)
				)
			)
		)
		(property "Value" ""
			(at 0 0 270)
			(layer "F.Fab")
			(effects
				(font
					(size 1.27 1.27)
				)
			)
		)
		(duplicate_pad_numbers_are_jumpers no)
		(fp_rect
			(start -0.500126 1.598422)
			(end 0.500126 -0.201422)
			(stroke
				(width 0)
				(type default)
			)
			(fill no)
			(layer "F.CrtYd")
		)
		(fp_line
			(start -0.500126 1.598422)
			(end -0.500126 -0.201422)
			(stroke
				(width 0.1)
				(type default)
			)
			(layer "F.Fab")
		)
		(fp_line
			(start 0.500126 1.598422)
			(end -0.500126 1.598422)
			(stroke
				(width 0.1)
				(type default)
			)
			(layer "F.Fab")
		)
		(fp_line
			(start -0.500126 -0.201422)
			(end 0.500126 -0.201422)
			(stroke
				(width 0.1)
				(type default)
			)
			(layer "F.Fab")
		)
		(fp_line
			(start 0.500126 -0.201422)
			(end 0.500126 1.598422)
			(stroke
				(width 0.1)
				(type default)
			)
			(layer "F.Fab")
		)
		(pad "1" smd rect
			(at 0 0 180)
			(size 0.889 0.9906)
			(layers "F.Cu" "F.Mask" "F.Paste")
			(net "PVDDQ_DEF")
		)
		(pad "2" smd rect
			(at 0 1.397 180)
			(size 0.889 0.9906)
			(layers "F.Cu" "F.Mask" "F.Paste")
			(net "GND")
		)
		(zone
			(layer "F.Cu")
			(hatch none 0.5)
			(connect_pads
				(clearance 0)
			)
			(min_thickness 0.25)
			(keepout
				(tracks allowed)
				(vias not_allowed)
				(pads allowed)
				(copperpour not_allowed)
				(footprints allowed)
			)
			(placement
				(enabled no)
				(sheetname "")
			)
			(fill
				(thermal_gap 0.5)
				(thermal_bridge_width 0.5)
				(island_removal_mode 0)
			)
			(polygon
				(pts
					(xy 244.7798 -150.3045) (xy 244.7798 -149.3139) (xy 245.2878 -149.3139) (xy 245.2878 -150.3045)
				)
			)
		)
		(zone
			(layer "F.Cu")
			(hatch none 0.5)
			(connect_pads
				(clearance 0)
			)
			(min_thickness 0.25)
			(keepout
				(tracks not_allowed)
				(vias allowed)
				(pads allowed)
				(copperpour not_allowed)
				(footprints allowed)
			)
			(placement
				(enabled no)
				(sheetname "")
			)
			(fill
				(thermal_gap 0.5)
				(thermal_bridge_width 0.5)
				(island_removal_mode 0)
			)
			(polygon
				(pts
					(xy 244.7798 -150.3045) (xy 244.7798 -149.3139) (xy 245.2878 -149.3139) (xy 245.2878 -150.3045)
				)
			)
		)
	)
)
